(kicad_sch
	(version 20250114)
	(generator "eeschema")
	(generator_version "9.0")
	(paper "A3")
	(title_block
		(title "SO-DIMM DDR5 Tester")
		(date "2025-11-26")
		(rev "1.3.0")
		(company "Antmicro Ltd.")
		(comment 1 "www.antmicro.com")
		(comment 2 "Antmicro Ltd")
	)
	(text "HyperRAM"
		(exclude_from_sim no)
		(at 13.97 19.05 0)
		(effects
			(font
				(size 2.9972 2.9972)
				(thickness 0.5994)
				(bold yes)
			)
			(justify left bottom)
		)
	)
	(text "(Q)SPI flash"
		(exclude_from_sim no)
		(at 14.605 142.875 0)
		(effects
			(font
				(size 2.9972 2.9972)
				(thickness 0.5994)
				(bold yes)
			)
			(justify left bottom)
		)
	)
	(text "Master SPI Quad (x4) configuration scheme\nFollows Figure 2-14 7 Series FPGAs Configuration User Guide\nUG470 (v1.13.1)"
		(exclude_from_sim no)
		(at 15.24 153.67 0)
		(effects
			(font
				(size 2.0066 2.0066)
			)
			(justify left bottom)
		)
	)
	(junction
		(at 210.82 218.44)
		(diameter 0)
		(color 0 0 0 0)
	)
	(junction
		(at 191.77 46.99)
		(diameter 0)
		(color 0 0 0 0)
	)
	(junction
		(at 233.68 57.15)
		(diameter 0)
		(color 0 0 0 0)
	)
	(junction
		(at 219.075 191.77)
		(diameter 0)
		(color 0 0 0 0)
	)
	(junction
		(at 233.68 95.25)
		(diameter 0)
		(color 0 0 0 0)
	)
	(junction
		(at 210.82 191.77)
		(diameter 0)
		(color 0 0 0 0)
	)
	(junction
		(at 191.77 57.15)
		(diameter 0)
		(color 0 0 0 0)
	)
	(junction
		(at 247.65 215.9)
		(diameter 0)
		(color 0 0 0 0)
	)
	(junction
		(at 255.905 57.15)
		(diameter 0)
		(color 0 0 0 0)
	)
	(junction
		(at 194.945 59.69)
		(diameter 0)
		(color 0 0 0 0)
	)
	(junction
		(at 248.285 57.15)
		(diameter 0)
		(color 0 0 0 0)
	)
	(junction
		(at 227.33 210.82)
		(diameter 0)
		(color 0 0 0 0)
	)
	(junction
		(at 263.525 57.15)
		(diameter 0)
		(color 0 0 0 0)
	)
	(junction
		(at 170.18 205.74)
		(diameter 0)
		(color 0 0 0 0)
	)
	(junction
		(at 219.075 213.36)
		(diameter 0)
		(color 0 0 0 0)
	)
	(junction
		(at 240.03 57.15)
		(diameter 0)
		(color 0 0 0 0)
	)
	(bus_entry
		(at 170.18 82.55)
		(size 2.54 2.54)
		(stroke
			(width 0)
			(type default)
		)
	)
	(bus_entry
		(at 170.18 87.63)
		(size 2.54 2.54)
		(stroke
			(width 0)
			(type default)
		)
	)
	(bus_entry
		(at 170.18 62.23)
		(size 2.54 2.54)
		(stroke
			(width 0)
			(type default)
		)
	)
	(bus_entry
		(at 170.18 80.01)
		(size 2.54 2.54)
		(stroke
			(width 0)
			(type default)
		)
	)
	(bus_entry
		(at 170.18 77.47)
		(size 2.54 2.54)
		(stroke
			(width 0)
			(type default)
		)
	)
	(bus_entry
		(at 259.715 213.36)
		(size 2.54 -2.54)
		(stroke
			(width 0)
			(type default)
		)
	)
	(bus_entry
		(at 259.715 218.44)
		(size 2.54 -2.54)
		(stroke
			(width 0)
			(type default)
		)
	)
	(bus_entry
		(at 170.18 74.93)
		(size 2.54 2.54)
		(stroke
			(width 0)
			(type default)
		)
	)
	(bus_entry
		(at 170.18 69.85)
		(size 2.54 2.54)
		(stroke
			(width 0)
			(type default)
		)
	)
	(bus_entry
		(at 259.715 215.9)
		(size 2.54 -2.54)
		(stroke
			(width 0)
			(type default)
		)
	)
	(bus_entry
		(at 170.18 92.71)
		(size 2.54 2.54)
		(stroke
			(width 0)
			(type default)
		)
	)
	(bus_entry
		(at 259.715 208.28)
		(size 2.54 -2.54)
		(stroke
			(width 0)
			(type default)
		)
	)
	(bus_entry
		(at 170.18 64.77)
		(size 2.54 2.54)
		(stroke
			(width 0)
			(type default)
		)
	)
	(bus_entry
		(at 170.18 85.09)
		(size 2.54 2.54)
		(stroke
			(width 0)
			(type default)
		)
	)
	(bus_entry
		(at 170.18 72.39)
		(size 2.54 2.54)
		(stroke
			(width 0)
			(type default)
		)
	)
	(bus_entry
		(at 259.715 210.82)
		(size 2.54 -2.54)
		(stroke
			(width 0)
			(type default)
		)
	)
	(bus_entry
		(at 170.18 54.61)
		(size 2.54 2.54)
		(stroke
			(width 0)
			(type default)
		)
	)
	(bus_entry
		(at 259.715 205.74)
		(size 2.54 -2.54)
		(stroke
			(width 0)
			(type default)
		)
	)
	(bus_entry
		(at 170.18 57.15)
		(size 2.54 2.54)
		(stroke
			(width 0)
			(type default)
		)
	)
	(bus
		(pts
			(xy 262.89 201.295) (xy 262.255 201.93)
		)
		(stroke
			(width 0)
			(type default)
		)
	)
	(bus
		(pts
			(xy 170.18 87.63) (xy 170.18 92.71)
		)
		(stroke
			(width 0)
			(type default)
		)
	)
	(wire
		(pts
			(xy 200.025 205.74) (xy 237.49 205.74)
		)
		(stroke
			(width 0)
			(type default)
		)
	)
	(bus
		(pts
			(xy 170.18 80.01) (xy 170.18 82.55)
		)
		(stroke
			(width 0)
			(type default)
		)
	)
	(bus
		(pts
			(xy 170.18 85.09) (xy 170.18 87.63)
		)
		(stroke
			(width 0)
			(type default)
		)
	)
	(wire
		(pts
			(xy 240.03 59.69) (xy 240.03 57.15)
		)
		(stroke
			(width 0)
			(type default)
		)
	)
	(bus
		(pts
			(xy 262.255 205.74) (xy 262.255 208.28)
		)
		(stroke
			(width 0)
			(type default)
		)
	)
	(bus
		(pts
			(xy 262.255 201.93) (xy 262.255 203.2)
		)
		(stroke
			(width 0)
			(type default)
		)
	)
	(wire
		(pts
			(xy 194.945 53.975) (xy 194.945 59.69)
		)
		(stroke
			(width 0)
			(type default)
		)
	)
	(wire
		(pts
			(xy 255.905 66.04) (xy 255.905 64.77)
		)
		(stroke
			(width 0)
			(type default)
		)
	)
	(wire
		(pts
			(xy 240.03 57.15) (xy 248.285 57.15)
		)
		(stroke
			(width 0)
			(type default)
		)
	)
	(bus
		(pts
			(xy 170.18 74.93) (xy 170.18 77.47)
		)
		(stroke
			(width 0)
			(type default)
		)
	)
	(wire
		(pts
			(xy 172.72 80.01) (xy 200.66 80.01)
		)
		(stroke
			(width 0)
			(type default)
		)
	)
	(wire
		(pts
			(xy 210.82 189.865) (xy 210.82 191.77)
		)
		(stroke
			(width 0)
			(type default)
		)
	)
	(wire
		(pts
			(xy 178.435 218.44) (xy 178.435 219.71)
		)
		(stroke
			(width 0)
			(type default)
		)
	)
	(wire
		(pts
			(xy 172.72 90.17) (xy 200.66 90.17)
		)
		(stroke
			(width 0)
			(type default)
		)
	)
	(wire
		(pts
			(xy 231.14 95.25) (xy 233.68 95.25)
		)
		(stroke
			(width 0)
			(type default)
		)
	)
	(wire
		(pts
			(xy 242.57 208.28) (xy 259.715 208.28)
		)
		(stroke
			(width 0)
			(type default)
		)
	)
	(bus
		(pts
			(xy 264.795 201.295) (xy 262.89 201.295)
		)
		(stroke
			(width 0)
			(type default)
		)
	)
	(polyline
		(pts
			(xy 12.065 135.255) (xy 407.67 135.255)
		)
		(stroke
			(width 0)
			(type default)
		)
	)
	(wire
		(pts
			(xy 240.03 66.04) (xy 240.03 64.77)
		)
		(stroke
			(width 0)
			(type default)
		)
	)
	(wire
		(pts
			(xy 210.82 218.44) (xy 259.715 218.44)
		)
		(stroke
			(width 0)
			(type default)
		)
	)
	(bus
		(pts
			(xy 170.18 53.34) (xy 170.18 54.61)
		)
		(stroke
			(width 0)
			(type default)
		)
	)
	(wire
		(pts
			(xy 227.33 200.025) (xy 227.33 210.82)
		)
		(stroke
			(width 0)
			(type default)
		)
	)
	(bus
		(pts
			(xy 170.18 57.15) (xy 170.18 62.23)
		)
		(stroke
			(width 0)
			(type default)
		)
	)
	(wire
		(pts
			(xy 210.82 218.44) (xy 210.82 200.025)
		)
		(stroke
			(width 0)
			(type default)
		)
	)
	(wire
		(pts
			(xy 172.72 85.09) (xy 200.66 85.09)
		)
		(stroke
			(width 0)
			(type default)
		)
	)
	(wire
		(pts
			(xy 191.77 45.72) (xy 191.77 46.99)
		)
		(stroke
			(width 0)
			(type default)
		)
	)
	(wire
		(pts
			(xy 227.33 210.82) (xy 237.49 210.82)
		)
		(stroke
			(width 0)
			(type default)
		)
	)
	(wire
		(pts
			(xy 233.68 57.15) (xy 240.03 57.15)
		)
		(stroke
			(width 0)
			(type default)
		)
	)
	(wire
		(pts
			(xy 219.075 213.36) (xy 237.49 213.36)
		)
		(stroke
			(width 0)
			(type default)
		)
	)
	(wire
		(pts
			(xy 247.65 215.9) (xy 259.715 215.9)
		)
		(stroke
			(width 0)
			(type default)
		)
	)
	(wire
		(pts
			(xy 170.18 205.74) (xy 179.705 205.74)
		)
		(stroke
			(width 0)
			(type default)
		)
	)
	(wire
		(pts
			(xy 263.525 55.88) (xy 263.525 57.15)
		)
		(stroke
			(width 0)
			(type default)
		)
	)
	(bus
		(pts
			(xy 170.18 54.61) (xy 170.18 57.15)
		)
		(stroke
			(width 0)
			(type default)
		)
	)
	(bus
		(pts
			(xy 167.64 52.07) (xy 168.91 52.07)
		)
		(stroke
			(width 0)
			(type default)
		)
	)
	(bus
		(pts
			(xy 170.18 82.55) (xy 170.18 85.09)
		)
		(stroke
			(width 0)
			(type default)
		)
	)
	(wire
		(pts
			(xy 231.14 57.15) (xy 233.68 57.15)
		)
		(stroke
			(width 0)
			(type default)
		)
	)
	(wire
		(pts
			(xy 255.905 57.15) (xy 263.525 57.15)
		)
		(stroke
			(width 0)
			(type default)
		)
	)
	(wire
		(pts
			(xy 200.025 210.82) (xy 227.33 210.82)
		)
		(stroke
			(width 0)
			(type default)
		)
	)
	(bus
		(pts
			(xy 170.18 69.85) (xy 170.18 72.39)
		)
		(stroke
			(width 0)
			(type default)
		)
	)
	(wire
		(pts
			(xy 170.18 205.105) (xy 170.18 205.74)
		)
		(stroke
			(width 0)
			(type default)
		)
	)
	(wire
		(pts
			(xy 210.82 191.77) (xy 219.075 191.77)
		)
		(stroke
			(width 0)
			(type default)
		)
	)
	(wire
		(pts
			(xy 170.18 205.74) (xy 170.18 209.55)
		)
		(stroke
			(width 0)
			(type default)
		)
	)
	(wire
		(pts
			(xy 170.18 214.63) (xy 170.18 219.71)
		)
		(stroke
			(width 0)
			(type default)
		)
	)
	(wire
		(pts
			(xy 172.72 74.93) (xy 200.66 74.93)
		)
		(stroke
			(width 0)
			(type default)
		)
	)
	(wire
		(pts
			(xy 200.025 213.36) (xy 219.075 213.36)
		)
		(stroke
			(width 0)
			(type default)
		)
	)
	(wire
		(pts
			(xy 172.72 87.63) (xy 200.66 87.63)
		)
		(stroke
			(width 0)
			(type default)
		)
	)
	(wire
		(pts
			(xy 200.66 57.15) (xy 191.77 57.15)
		)
		(stroke
			(width 0)
			(type default)
		)
	)
	(wire
		(pts
			(xy 247.65 215.9) (xy 247.65 221.615)
		)
		(stroke
			(width 0)
			(type default)
		)
	)
	(wire
		(pts
			(xy 242.57 213.36) (xy 259.715 213.36)
		)
		(stroke
			(width 0)
			(type default)
		)
	)
	(wire
		(pts
			(xy 219.075 191.77) (xy 227.33 191.77)
		)
		(stroke
			(width 0)
			(type default)
		)
	)
	(wire
		(pts
			(xy 172.72 59.69) (xy 194.945 59.69)
		)
		(stroke
			(width 0)
			(type default)
		)
	)
	(bus
		(pts
			(xy 170.18 77.47) (xy 170.18 80.01)
		)
		(stroke
			(width 0)
			(type default)
		)
	)
	(wire
		(pts
			(xy 200.025 208.28) (xy 237.49 208.28)
		)
		(stroke
			(width 0)
			(type default)
		)
	)
	(wire
		(pts
			(xy 263.525 57.15) (xy 263.525 59.69)
		)
		(stroke
			(width 0)
			(type default)
		)
	)
	(wire
		(pts
			(xy 172.72 77.47) (xy 200.66 77.47)
		)
		(stroke
			(width 0)
			(type default)
		)
	)
	(wire
		(pts
			(xy 242.57 210.82) (xy 259.715 210.82)
		)
		(stroke
			(width 0)
			(type default)
		)
	)
	(wire
		(pts
			(xy 191.77 53.975) (xy 191.77 57.15)
		)
		(stroke
			(width 0)
			(type default)
		)
	)
	(wire
		(pts
			(xy 172.72 95.25) (xy 200.66 95.25)
		)
		(stroke
			(width 0)
			(type default)
		)
	)
	(wire
		(pts
			(xy 172.72 82.55) (xy 200.66 82.55)
		)
		(stroke
			(width 0)
			(type default)
		)
	)
	(wire
		(pts
			(xy 233.68 59.69) (xy 233.68 57.15)
		)
		(stroke
			(width 0)
			(type default)
		)
	)
	(bus
		(pts
			(xy 170.18 64.77) (xy 170.18 69.85)
		)
		(stroke
			(width 0)
			(type default)
		)
	)
	(bus
		(pts
			(xy 168.91 52.07) (xy 170.18 53.34)
		)
		(stroke
			(width 0)
			(type default)
		)
	)
	(wire
		(pts
			(xy 248.285 59.69) (xy 248.285 57.15)
		)
		(stroke
			(width 0)
			(type default)
		)
	)
	(wire
		(pts
			(xy 194.945 46.99) (xy 194.945 48.895)
		)
		(stroke
			(width 0)
			(type default)
		)
	)
	(wire
		(pts
			(xy 227.33 194.945) (xy 227.33 191.77)
		)
		(stroke
			(width 0)
			(type default)
		)
	)
	(wire
		(pts
			(xy 231.14 59.69) (xy 233.68 59.69)
		)
		(stroke
			(width 0)
			(type default)
		)
	)
	(bus
		(pts
			(xy 170.18 62.23) (xy 170.18 64.77)
		)
		(stroke
			(width 0)
			(type default)
		)
	)
	(wire
		(pts
			(xy 219.075 191.77) (xy 219.075 194.945)
		)
		(stroke
			(width 0)
			(type default)
		)
	)
	(wire
		(pts
			(xy 172.72 67.31) (xy 200.66 67.31)
		)
		(stroke
			(width 0)
			(type default)
		)
	)
	(wire
		(pts
			(xy 172.72 64.77) (xy 200.66 64.77)
		)
		(stroke
			(width 0)
			(type default)
		)
	)
	(bus
		(pts
			(xy 262.255 213.36) (xy 262.255 215.9)
		)
		(stroke
			(width 0)
			(type default)
		)
	)
	(wire
		(pts
			(xy 179.705 218.44) (xy 178.435 218.44)
		)
		(stroke
			(width 0)
			(type default)
		)
	)
	(wire
		(pts
			(xy 263.525 66.04) (xy 263.525 64.77)
		)
		(stroke
			(width 0)
			(type default)
		)
	)
	(wire
		(pts
			(xy 194.945 59.69) (xy 200.66 59.69)
		)
		(stroke
			(width 0)
			(type default)
		)
	)
	(wire
		(pts
			(xy 255.905 57.15) (xy 255.905 59.69)
		)
		(stroke
			(width 0)
			(type default)
		)
	)
	(bus
		(pts
			(xy 170.18 72.39) (xy 170.18 74.93)
		)
		(stroke
			(width 0)
			(type default)
		)
	)
	(wire
		(pts
			(xy 248.285 57.15) (xy 255.905 57.15)
		)
		(stroke
			(width 0)
			(type default)
		)
	)
	(wire
		(pts
			(xy 191.77 46.99) (xy 191.77 48.895)
		)
		(stroke
			(width 0)
			(type default)
		)
	)
	(wire
		(pts
			(xy 200.025 218.44) (xy 210.82 218.44)
		)
		(stroke
			(width 0)
			(type default)
		)
	)
	(wire
		(pts
			(xy 172.72 72.39) (xy 200.66 72.39)
		)
		(stroke
			(width 0)
			(type default)
		)
	)
	(wire
		(pts
			(xy 233.68 95.25) (xy 233.68 97.155)
		)
		(stroke
			(width 0)
			(type default)
		)
	)
	(bus
		(pts
			(xy 262.255 203.2) (xy 262.255 205.74)
		)
		(stroke
			(width 0)
			(type default)
		)
	)
	(bus
		(pts
			(xy 262.255 210.82) (xy 262.255 213.36)
		)
		(stroke
			(width 0)
			(type default)
		)
	)
	(bus
		(pts
			(xy 262.255 208.28) (xy 262.255 210.82)
		)
		(stroke
			(width 0)
			(type default)
		)
	)
	(wire
		(pts
			(xy 200.025 215.9) (xy 247.65 215.9)
		)
		(stroke
			(width 0)
			(type default)
		)
	)
	(wire
		(pts
			(xy 248.285 66.04) (xy 248.285 64.77)
		)
		(stroke
			(width 0)
			(type default)
		)
	)
	(wire
		(pts
			(xy 210.82 191.77) (xy 210.82 194.945)
		)
		(stroke
			(width 0)
			(type default)
		)
	)
	(wire
		(pts
			(xy 242.57 205.74) (xy 259.715 205.74)
		)
		(stroke
			(width 0)
			(type default)
		)
	)
	(wire
		(pts
			(xy 172.72 57.15) (xy 191.77 57.15)
		)
		(stroke
			(width 0)
			(type default)
		)
	)
	(wire
		(pts
			(xy 219.075 213.36) (xy 219.075 200.025)
		)
		(stroke
			(width 0)
			(type default)
		)
	)
	(wire
		(pts
			(xy 191.77 46.99) (xy 194.945 46.99)
		)
		(stroke
			(width 0)
			(type default)
		)
	)
	(wire
		(pts
			(xy 231.14 92.71) (xy 233.68 92.71)
		)
		(stroke
			(width 0)
			(type default)
		)
	)
	(wire
		(pts
			(xy 233.68 92.71) (xy 233.68 95.25)
		)
		(stroke
			(width 0)
			(type default)
		)
	)
	(label "FLASH.IO3"
		(at 259.715 213.36 180)
		(effects
			(font
				(size 1.27 1.27)
			)
			(justify right bottom)
		)
	)
	(label "FLASH.IO1"
		(at 259.715 208.28 180)
		(effects
			(font
				(size 1.27 1.27)
			)
			(justify right bottom)
		)
	)
	(label "HyperRAM.~{CS}"
		(at 172.72 59.69 0)
		(effects
			(font
				(size 1.27 1.27)
			)
			(justify left bottom)
		)
	)
	(label "FLASH.IO2"
		(at 259.715 210.82 180)
		(effects
			(font
				(size 1.27 1.27)
			)
			(justify right bottom)
		)
	)
	(label "FLASH.~{CS}"
		(at 259.715 218.44 180)
		(effects
			(font
				(size 1.27 1.27)
			)
			(justify right bottom)
		)
	)
	(label "HyperRAM.DQ3"
		(at 172.72 80.01 0)
		(effects
			(font
				(size 1.27 1.27)
			)
			(justify left bottom)
		)
	)
	(label "HyperRAM.DQ7"
		(at 172.72 90.17 0)
		(effects
			(font
				(size 1.27 1.27)
			)
			(justify left bottom)
		)
	)
	(label "IO3"
		(at 203.835 213.36 180)
		(effects
			(font
				(size 1.27 1.27)
			)
			(justify right bottom)
		)
	)
	(label "HyperRAM.~{RESET}"
		(at 172.72 57.15 0)
		(effects
			(font
				(size 1.27 1.27)
			)
			(justify left bottom)
		)
	)
	(label "HyperRAM.DQ1"
		(at 172.72 74.93 0)
		(effects
			(font
				(size 1.27 1.27)
			)
			(justify left bottom)
		)
	)
	(label "FLASH.IO0"
		(at 259.715 205.74 180)
		(effects
			(font
				(size 1.27 1.27)
			)
			(justify right bottom)
		)
	)
	(label "IO1"
		(at 203.835 208.28 180)
		(effects
			(font
				(size 1.27 1.27)
			)
			(justify right bottom)
		)
	)
	(label "HyperRAM.DQ2"
		(at 172.72 77.47 0)
		(effects
			(font
				(size 1.27 1.27)
			)
			(justify left bottom)
		)
	)
	(label "HyperRAM.DQ5"
		(at 172.72 85.09 0)
		(effects
			(font
				(size 1.27 1.27)
			)
			(justify left bottom)
		)
	)
	(label "HyperRAM.RWDS"
		(at 172.72 95.25 0)
		(effects
			(font
				(size 1.27 1.27)
			)
			(justify left bottom)
		)
	)
	(label "HyperRAM.DQ0"
		(at 172.72 72.39 0)
		(effects
			(font
				(size 1.27 1.27)
			)
			(justify left bottom)
		)
	)
	(label "HyperRAM.DQ6"
		(at 172.72 87.63 0)
		(effects
			(font
				(size 1.27 1.27)
			)
			(justify left bottom)
		)
	)
	(label "IO0"
		(at 203.835 205.74 180)
		(effects
			(font
				(size 1.27 1.27)
			)
			(justify right bottom)
		)
	)
	(label "HyperRAM.CK_P"
		(at 172.72 64.77 0)
		(effects
			(font
				(size 1.27 1.27)
			)
			(justify left bottom)
		)
	)
	(label "HyperRAM.DQ4"
		(at 172.72 82.55 0)
		(effects
			(font
				(size 1.27 1.27)
			)
			(justify left bottom)
		)
	)
	(label "IO2"
		(at 203.835 210.82 180)
		(effects
			(font
				(size 1.27 1.27)
			)
			(justify right bottom)
		)
	)
	(label "FLASH.SCK"
		(at 259.715 215.9 180)
		(effects
			(font
				(size 1.27 1.27)
			)
			(justify right bottom)
		)
	)
	(label "HyperRAM.CK_N"
		(at 172.72 67.31 0)
		(effects
			(font
				(size 1.27 1.27)
			)
			(justify left bottom)
		)
	)
	(hierarchical_label "FLASH{QSPI}"
		(shape bidirectional)
		(at 264.795 201.295 0)
		(effects
			(font
				(size 1.27 1.27)
			)
			(justify left)
		)
	)
	(hierarchical_label "HyperRAM{HyperBus}"
		(shape bidirectional)
		(at 167.64 52.07 180)
		(effects
			(font
				(size 1.27 1.27)
			)
			(justify right)
		)
	)
	(symbol
		(lib_id "antmicroCapacitors0603:C_47u_0603")
		(at 240.03 59.69 270)
		(unit 1)
		(exclude_from_sim no)
		(in_bom yes)
		(on_board yes)
		(dnp no)
		(property "Reference" "C1"
			(at 240.665 60.325 90)
			(effects
				(font
					(size 1.27 1.27)
				)
				(justify left)
			)
		)
		(property "Value" "C_47u_0603"
			(at 229.87 80.01 0)
			(effects
				(font
					(size 1.27 1.27)
					(thickness 0.15)
				)
				(justify left bottom)
				(hide yes)
			)
		)
		(property "Footprint" "antmicro-footprints:C_0603_1608Metric"
			(at 227.33 80.01 0)
			(effects
				(font
					(size 1.27 1.27)
					(thickness 0.15)
				)
				(justify left bottom)
				(hide yes)
			)
		)
		(property "Datasheet" "https://www.murata.com/products/productdetail?partno=GRM188R60J476ME15%23"
			(at 224.79 80.01 0)
			(effects
				(font
					(size 1.27 1.27)
					(thickness 0.15)
				)
				(justify left bottom)
				(hide yes)
			)
		)
		(property "Description" ""
			(at 240.03 59.69 0)
			(effects
				(font
					(size 1.27 1.27)
				)
			)
		)
		(property "Manufacturer" "Murata"
			(at 219.71 80.01 0)
			(effects
				(font
					(size 1.27 1.27)
					(thickness 0.15)
				)
				(justify left bottom)
				(hide yes)
			)
		)
		(property "MPN" "GRM188R60J476ME15D"
			(at 222.25 80.01 0)
			(effects
				(font
					(size 1.27 1.27)
					(thickness 0.15)
				)
				(justify left bottom)
				(hide yes)
			)
		)
		(property "Val" "47u"
			(at 240.665 64.135 90)
			(effects
				(font
					(size 1.27 1.27)
					(thickness 0.15)
				)
				(justify left)
			)
		)
		(property "License" "Apache-2.0"
			(at 217.17 80.01 0)
			(effects
				(font
					(size 1.27 1.27)
					(thickness 0.15)
				)
				(justify left bottom)
				(hide yes)
			)
		)
		(property "Author" "Antmicro"
			(at 214.63 80.01 0)
			(effects
				(font
					(size 1.27 1.27)
					(thickness 0.15)
				)
				(justify left bottom)
				(hide yes)
			)
		)
		(property "Voltage" ""
			(at 212.09 80.01 0)
			(effects
				(font
					(size 1.27 1.27)
				)
				(justify left bottom)
				(hide yes)
			)
		)
		(property "Dielectric" ""
			(at 209.55 80.01 0)
			(effects
				(font
					(size 1.27 1.27)
				)
				(justify left bottom)
				(hide yes)
			)
		)
		(pin "1"
		)
		(pin "2"
		)
		(instances
			(project "sodimm-ddr5-tester"
				(path ""
					(reference "C1")
					(unit 1)
				)
			)
		)
	)
	(symbol
		(lib_id "antmicroCapacitors0402:C_100n_0402")
		(at 255.905 59.69 270)
		(unit 1)
		(exclude_from_sim no)
		(in_bom yes)
		(on_board yes)
		(dnp no)
		(property "Reference" "C3"
			(at 256.54 60.325 90)
			(effects
				(font
					(size 1.27 1.27)
				)
				(justify left)
			)
		)
		(property "Value" "C_100n_0402"
			(at 245.745 80.01 0)
			(effects
				(font
					(size 1.27 1.27)
					(thickness 0.15)
				)
				(justify left bottom)
				(hide yes)
			)
		)
		(property "Footprint" "antmicro-footprints:C_0402_1005Metric"
			(at 243.205 80.01 0)
			(effects
				(font
					(size 1.27 1.27)
					(thickness 0.15)
				)
				(justify left bottom)
				(hide yes)
			)
		)
		(property "Datasheet" "https://www.murata.com/products/productdetail?partno=GRM155R61H104KE14%23"
			(at 240.665 80.01 0)
			(effects
				(font
					(size 1.27 1.27)
					(thickness 0.15)
				)
				(justify left bottom)
				(hide yes)
			)
		)
		(property "Description" ""
			(at 255.905 59.69 0)
			(effects
				(font
					(size 1.27 1.27)
				)
			)
		)
		(property "Manufacturer" "Murata"
			(at 235.585 80.01 0)
			(effects
				(font
					(size 1.27 1.27)
					(thickness 0.15)
				)
				(justify left bottom)
				(hide yes)
			)
		)
		(property "MPN" "GRM155R61H104KE14D"
			(at 238.125 80.01 0)
			(effects
				(font
					(size 1.27 1.27)
					(thickness 0.15)
				)
				(justify left bottom)
				(hide yes)
			)
		)
		(property "Val" "100n"
			(at 256.54 64.135 90)
			(effects
				(font
					(size 1.27 1.27)
					(thickness 0.15)
				)
				(justify left)
			)
		)
		(property "License" "Apache-2.0"
			(at 233.045 80.01 0)
			(effects
				(font
					(size 1.27 1.27)
					(thickness 0.15)
				)
				(justify left bottom)
				(hide yes)
			)
		)
		(property "Author" "Antmicro"
			(at 230.505 80.01 0)
			(effects
				(font
					(size 1.27 1.27)
					(thickness 0.15)
				)
				(justify left bottom)
				(hide yes)
			)
		)
		(property "Voltage" "50V"
			(at 227.965 80.01 0)
			(effects
				(font
					(size 1.27 1.27)
				)
				(justify left bottom)
				(hide yes)
			)
		)
		(property "Dielectric" "X5R"
			(at 225.425 80.01 0)
			(effects
				(font
					(size 1.27 1.27)
				)
				(justify left bottom)
				(hide yes)
			)
		)
		(pin "1"
		)
		(pin "2"
		)
		(instances
			(project "sodimm-ddr5-tester"
				(path ""
					(reference "C3")
					(unit 1)
				)
			)
		)
	)
	(symbol
		(lib_id "antmicropower:GND")
		(at 240.03 66.04 0)
		(unit 1)
		(exclude_from_sim no)
		(in_bom yes)
		(on_board yes)
		(dnp no)
		(fields_autoplaced yes)
		(property "Reference" "#PWR04"
			(at 240.03 72.39 0)
			(effects
				(font
					(size 1.27 1.27)
				)
				(hide yes)
			)
		)
		(property "Value" "GND"
			(at 242.57 67.31 0)
			(effects
				(font
					(size 1.27 1.27)
					(thickness 0.15)
				)
				(justify left)
			)
		)
		(property "Footprint" ""
			(at 248.92 73.66 0)
			(effects
				(font
					(size 1.27 1.27)
					(thickness 0.15)
				)
				(justify left bottom)
				(hide yes)
			)
		)
		(property "Datasheet" ""
			(at 248.92 78.74 0)
			(effects
				(font
					(size 1.27 1.27)
					(thickness 0.15)
				)
				(justify left bottom)
				(hide yes)
			)
		)
		(property "Description" ""
			(at 248.92 81.28 0)
			(effects
				(font
					(size 1.27 1.27)
				)
				(justify left bottom)
				(hide yes)
			)
		)
		(property "Author" "Antmicro"
			(at 248.92 73.66 0)
			(effects
				(font
					(size 1.27 1.27)
					(thickness 0.15)
				)
				(justify left bottom)
				(hide yes)
			)
		)
		(property "License" "Apache-2.0"
			(at 248.92 76.2 0)
			(effects
				(font
					(size 1.27 1.27)
					(thickness 0.15)
				)
				(justify left bottom)
				(hide yes)
			)
		)
		(pin "1"
		)
		(instances
			(project "sodimm-ddr5-tester"
				(path ""
					(reference "#PWR04")
					(unit 1)
				)
			)
		)
	)
	(symbol
		(lib_id "antmicroResistors0402:R_10k_0402")
		(at 191.77 48.895 270)
		(unit 1)
		(exclude_from_sim no)
		(in_bom yes)
		(on_board yes)
		(dnp no)
		(property "Reference" "R1"
			(at 189.865 50.1651 90)
			(effects
				(font
					(size 1.27 1.27)
				)
				(justify right)
			)
		)
		(property "Value" "R_10k_0402"
			(at 179.07 69.215 0)
			(effects
				(font
					(size 1.27 1.27)
					(thickness 0.15)
				)
				(justify left bottom)
				(hide yes)
			)
		)
		(property "Footprint" "antmicro-footprints:R_0402_1005Metric"
			(at 176.53 69.215 0)
			(effects
				(font
					(size 1.27 1.27)
					(thickness 0.15)
				)
				(justify left bottom)
				(hide yes)
			)
		)
		(property "Datasheet" "https://www.bourns.com/docs/product-datasheets/cr.pdf"
			(at 173.99 69.215 0)
			(effects
				(font
					(size 1.27 1.27)
					(thickness 0.15)
				)
				(justify left bottom)
				(hide yes)
			)
		)
		(property "Description" ""
			(at 191.77 48.895 0)
			(effects
				(font
					(size 1.27 1.27)
				)
			)
		)
		(property "Manufacturer" "Bourns"
			(at 168.91 69.215 0)
			(effects
				(font
					(size 1.27 1.27)
					(thickness 0.15)
				)
				(justify left bottom)
				(hide yes)
			)
		)
		(property "MPN" "CR0402-FX-1002GLF"
			(at 171.45 69.215 0)
			(effects
				(font
					(size 1.27 1.27)
					(thickness 0.15)
				)
				(justify left bottom)
				(hide yes)
			)
		)
		(property "Val" "10k"
			(at 189.865 53.34 90)
			(effects
				(font
					(size 1.27 1.27)
					(thickness 0.15)
				)
				(justify right)
			)
		)
		(property "License" "Apache-2.0"
			(at 166.37 69.215 0)
			(effects
				(font
					(size 1.27 1.27)
					(thickness 0.15)
				)
				(justify left bottom)
				(hide yes)
			)
		)
		(property "Author" "Antmicro"
			(at 163.83 69.215 0)
			(effects
				(font
					(size 1.27 1.27)
					(thickness 0.15)
				)
				(justify left bottom)
				(hide yes)
			)
		)
		(property "Tolerance" "1%"
			(at 181.61 69.215 0)
			(effects
				(font
					(size 1.27 1.27)
				)
				(justify left bottom)
				(hide yes)
			)
		)
		(pin "1"
		)
		(pin "2"
		)
		(instances
			(project "sodimm-ddr5-tester"
				(path ""
					(reference "R1")
					(unit 1)
				)
			)
		)
	)
	(symbol
		(lib_id "antmicropower:GND")
		(at 248.285 66.04 0)
		(unit 1)
		(exclude_from_sim no)
		(in_bom yes)
		(on_board yes)
		(dnp no)
		(fields_autoplaced yes)
		(property "Reference" "#PWR05"
			(at 248.285 72.39 0)
			(effects
				(font
					(size 1.27 1.27)
				)
				(hide yes)
			)
		)
		(property "Value" "GND"
			(at 250.19 67.31 0)
			(effects
				(font
					(size 1.27 1.27)
					(thickness 0.15)
				)
				(justify left)
			)
		)
		(property "Footprint" ""
			(at 257.175 73.66 0)
			(effects
				(font
					(size 1.27 1.27)
					(thickness 0.15)
				)
				(justify left bottom)
				(hide yes)
			)
		)
		(property "Datasheet" ""
			(at 257.175 78.74 0)
			(effects
				(font
					(size 1.27 1.27)
					(thickness 0.15)
				)
				(justify left bottom)
				(hide yes)
			)
		)
		(property "Description" ""
			(at 257.175 81.28 0)
			(effects
				(font
					(size 1.27 1.27)
				)
				(justify left bottom)
				(hide yes)
			)
		)
		(property "Author" "Antmicro"
			(at 257.175 73.66 0)
			(effects
				(font
					(size 1.27 1.27)
					(thickness 0.15)
				)
				(justify left bottom)
				(hide yes)
			)
		)
		(property "License" "Apache-2.0"
			(at 257.175 76.2 0)
			(effects
				(font
					(size 1.27 1.27)
					(thickness 0.15)
				)
				(justify left bottom)
				(hide yes)
			)
		)
		(pin "1"
		)
		(instances
			(project "sodimm-ddr5-tester"
				(path ""
					(reference "#PWR05")
					(unit 1)
				)
			)
		)
	)
	(symbol
		(lib_id "antmicropower:GND")
		(at 255.905 66.04 0)
		(unit 1)
		(exclude_from_sim no)
		(in_bom yes)
		(on_board yes)
		(dnp no)
		(fields_autoplaced yes)
		(property "Reference" "#PWR06"
			(at 255.905 72.39 0)
			(effects
				(font
					(size 1.27 1.27)
				)
				(hide yes)
			)
		)
		(property "Value" "GND"
			(at 257.81 67.31 0)
			(effects
				(font
					(size 1.27 1.27)
					(thickness 0.15)
				)
				(justify left)
			)
		)
		(property "Footprint" ""
			(at 264.795 73.66 0)
			(effects
				(font
					(size 1.27 1.27)
					(thickness 0.15)
				)
				(justify left bottom)
				(hide yes)
			)
		)
		(property "Datasheet" ""
			(at 264.795 78.74 0)
			(effects
				(font
					(size 1.27 1.27)
					(thickness 0.15)
				)
				(justify left bottom)
				(hide yes)
			)
		)
		(property "Description" ""
			(at 264.795 81.28 0)
			(effects
				(font
					(size 1.27 1.27)
				)
				(justify left bottom)
				(hide yes)
			)
		)
		(property "Author" "Antmicro"
			(at 264.795 73.66 0)
			(effects
				(font
					(size 1.27 1.27)
					(thickness 0.15)
				)
				(justify left bottom)
				(hide yes)
			)
		)
		(property "License" "Apache-2.0"
			(at 264.795 76.2 0)
			(effects
				(font
					(size 1.27 1.27)
					(thickness 0.15)
				)
				(justify left bottom)
				(hide yes)
			)
		)
		(pin "1"
		)
		(instances
			(project "sodimm-ddr5-tester"
				(path ""
					(reference "#PWR06")
					(unit 1)
				)
			)
		)
	)
	(symbol
		(lib_id "antmicroCapacitors0402:C_100n_0402")
		(at 248.285 59.69 270)
		(unit 1)
		(exclude_from_sim no)
		(in_bom yes)
		(on_board yes)
		(dnp no)
		(property "Reference" "C2"
			(at 248.92 60.325 90)
			(effects
				(font
					(size 1.27 1.27)
				)
				(justify left)
			)
		)
		(property "Value" "C_100n_0402"
			(at 238.125 80.01 0)
			(effects
				(font
					(size 1.27 1.27)
					(thickness 0.15)
				)
				(justify left bottom)
				(hide yes)
			)
		)
		(property "Footprint" "antmicro-footprints:C_0402_1005Metric"
			(at 235.585 80.01 0)
			(effects
				(font
					(size 1.27 1.27)
					(thickness 0.15)
				)
				(justify left bottom)
				(hide yes)
			)
		)
		(property "Datasheet" "https://www.murata.com/products/productdetail?partno=GRM155R61H104KE14%23"
			(at 233.045 80.01 0)
			(effects
				(font
					(size 1.27 1.27)
					(thickness 0.15)
				)
				(justify left bottom)
				(hide yes)
			)
		)
		(property "Description" ""
			(at 248.285 59.69 0)
			(effects
				(font
					(size 1.27 1.27)
				)
			)
		)
		(property "Manufacturer" "Murata"
			(at 227.965 80.01 0)
			(effects
				(font
					(size 1.27 1.27)
					(thickness 0.15)
				)
				(justify left bottom)
				(hide yes)
			)
		)
		(property "MPN" "GRM155R61H104KE14D"
			(at 230.505 80.01 0)
			(effects
				(font
					(size 1.27 1.27)
					(thickness 0.15)
				)
				(justify left bottom)
				(hide yes)
			)
		)
		(property "Val" "100n"
			(at 248.92 64.135 90)
			(effects
				(font
					(size 1.27 1.27)
					(thickness 0.15)
				)
				(justify left)
			)
		)
		(property "License" "Apache-2.0"
			(at 225.425 80.01 0)
			(effects
				(font
					(size 1.27 1.27)
					(thickness 0.15)
				)
				(justify left bottom)
				(hide yes)
			)
		)
		(property "Author" "Antmicro"
			(at 222.885 80.01 0)
			(effects
				(font
					(size 1.27 1.27)
					(thickness 0.15)
				)
				(justify left bottom)
				(hide yes)
			)
		)
		(property "Voltage" "50V"
			(at 220.345 80.01 0)
			(effects
				(font
					(size 1.27 1.27)
				)
				(justify left bottom)
				(hide yes)
			)
		)
		(property "Dielectric" "X5R"
			(at 217.805 80.01 0)
			(effects
				(font
					(size 1.27 1.27)
				)
				(justify left bottom)
				(hide yes)
			)
		)
		(pin "1"
		)
		(pin "2"
		)
		(instances
			(project "sodimm-ddr5-tester"
				(path ""
					(reference "C2")
					(unit 1)
				)
			)
		)
	)
	(symbol
		(lib_id "antmicroResistors0402:R_10k_0402")
		(at 194.945 48.895 270)
		(unit 1)
		(exclude_from_sim no)
		(in_bom yes)
		(on_board yes)
		(dnp no)
		(fields_autoplaced yes)
		(property "Reference" "R2"
			(at 196.85 50.165 90)
			(effects
				(font
					(size 1.27 1.27)
				)
				(justify left)
			)
		)
		(property "Value" "R_10k_0402"
			(at 182.245 69.215 0)
			(effects
				(font
					(size 1.27 1.27)
					(thickness 0.15)
				)
				(justify left bottom)
				(hide yes)
			)
		)
		(property "Footprint" "antmicro-footprints:R_0402_1005Metric"
			(at 179.705 69.215 0)
			(effects
				(font
					(size 1.27 1.27)
					(thickness 0.15)
				)
				(justify left bottom)
				(hide yes)
			)
		)
		(property "Datasheet" "https://www.bourns.com/docs/product-datasheets/cr.pdf"
			(at 177.165 69.215 0)
			(effects
				(font
					(size 1.27 1.27)
					(thickness 0.15)
				)
				(justify left bottom)
				(hide yes)
			)
		)
		(property "Description" ""
			(at 194.945 48.895 0)
			(effects
				(font
					(size 1.27 1.27)
				)
			)
		)
		(property "Manufacturer" "Bourns"
			(at 172.085 69.215 0)
			(effects
				(font
					(size 1.27 1.27)
					(thickness 0.15)
				)
				(justify left bottom)
				(hide yes)
			)
		)
		(property "MPN" "CR0402-FX-1002GLF"
			(at 174.625 69.215 0)
			(effects
				(font
					(size 1.27 1.27)
					(thickness 0.15)
				)
				(justify left bottom)
				(hide yes)
			)
		)
		(property "Val" "10k"
			(at 196.85 53.3399 90)
			(effects
				(font
					(size 1.27 1.27)
					(thickness 0.15)
				)
				(justify left)
			)
		)
		(property "License" "Apache-2.0"
			(at 169.545 69.215 0)
			(effects
				(font
					(size 1.27 1.27)
					(thickness 0.15)
				)
				(justify left bottom)
				(hide yes)
			)
		)
		(property "Author" "Antmicro"
			(at 167.005 69.215 0)
			(effects
				(font
					(size 1.27 1.27)
					(thickness 0.15)
				)
				(justify left bottom)
				(hide yes)
			)
		)
		(property "Tolerance" "1%"
			(at 184.785 69.215 0)
			(effects
				(font
					(size 1.27 1.27)
				)
				(justify left bottom)
				(hide yes)
			)
		)
		(pin "1"
		)
		(pin "2"
		)
		(instances
			(project "sodimm-ddr5-tester"
				(path ""
					(reference "R2")
					(unit 1)
				)
			)
		)
	)
	(symbol
		(lib_id "antmicropower:GND")
		(at 233.68 97.155 0)
		(unit 1)
		(exclude_from_sim no)
		(in_bom yes)
		(on_board yes)
		(dnp no)
		(fields_autoplaced yes)
		(property "Reference" "#PWR03"
			(at 233.68 103.505 0)
			(effects
				(font
					(size 1.27 1.27)
				)
				(hide yes)
			)
		)
		(property "Value" "GND"
			(at 236.22 98.425 0)
			(effects
				(font
					(size 1.27 1.27)
					(thickness 0.15)
				)
				(justify left)
			)
		)
		(property "Footprint" ""
			(at 242.57 104.775 0)
			(effects
				(font
					(size 1.27 1.27)
					(thickness 0.15)
				)
				(justify left bottom)
				(hide yes)
			)
		)
		(property "Datasheet" ""
			(at 242.57 109.855 0)
			(effects
				(font
					(size 1.27 1.27)
					(thickness 0.15)
				)
				(justify left bottom)
				(hide yes)
			)
		)
		(property "Description" ""
			(at 242.57 112.395 0)
			(effects
				(font
					(size 1.27 1.27)
				)
				(justify left bottom)
				(hide yes)
			)
		)
		(property "Author" "Antmicro"
			(at 242.57 104.775 0)
			(effects
				(font
					(size 1.27 1.27)
					(thickness 0.15)
				)
				(justify left bottom)
				(hide yes)
			)
		)
		(property "License" "Apache-2.0"
			(at 242.57 107.315 0)
			(effects
				(font
					(size 1.27 1.27)
					(thickness 0.15)
				)
				(justify left bottom)
				(hide yes)
			)
		)
		(pin "1"
		)
		(instances
			(project "sodimm-ddr5-tester"
				(path ""
					(reference "#PWR03")
					(unit 1)
				)
			)
		)
	)
	(symbol
		(lib_id "antmicroCapacitors0402:C_100n_0402")
		(at 263.525 59.69 270)
		(unit 1)
		(exclude_from_sim no)
		(in_bom yes)
		(on_board yes)
		(dnp no)
		(property "Reference" "C4"
			(at 264.16 60.325 90)
			(effects
				(font
					(size 1.27 1.27)
				)
				(justify left)
			)
		)
		(property "Value" "C_100n_0402"
			(at 253.365 80.01 0)
			(effects
				(font
					(size 1.27 1.27)
					(thickness 0.15)
				)
				(justify left bottom)
				(hide yes)
			)
		)
		(property "Footprint" "antmicro-footprints:C_0402_1005Metric"
			(at 250.825 80.01 0)
			(effects
				(font
					(size 1.27 1.27)
					(thickness 0.15)
				)
				(justify left bottom)
				(hide yes)
			)
		)
		(property "Datasheet" "https://www.murata.com/products/productdetail?partno=GRM155R61H104KE14%23"
			(at 248.285 80.01 0)
			(effects
				(font
					(size 1.27 1.27)
					(thickness 0.15)
				)
				(justify left bottom)
				(hide yes)
			)
		)
		(property "Description" ""
			(at 263.525 59.69 0)
			(effects
				(font
					(size 1.27 1.27)
				)
			)
		)
		(property "Manufacturer" "Murata"
			(at 243.205 80.01 0)
			(effects
				(font
					(size 1.27 1.27)
					(thickness 0.15)
				)
				(justify left bottom)
				(hide yes)
			)
		)
		(property "MPN" "GRM155R61H104KE14D"
			(at 245.745 80.01 0)
			(effects
				(font
					(size 1.27 1.27)
					(thickness 0.15)
				)
				(justify left bottom)
				(hide yes)
			)
		)
		(property "Val" "100n"
			(at 264.16 64.135 90)
			(effects
				(font
					(size 1.27 1.27)
					(thickness 0.15)
				)
				(justify left)
			)
		)
		(property "License" "Apache-2.0"
			(at 240.665 80.01 0)
			(effects
				(font
					(size 1.27 1.27)
					(thickness 0.15)
				)
				(justify left bottom)
				(hide yes)
			)
		)
		(property "Author" "Antmicro"
			(at 238.125 80.01 0)
			(effects
				(font
					(size 1.27 1.27)
					(thickness 0.15)
				)
				(justify left bottom)
				(hide yes)
			)
		)
		(property "Voltage" "50V"
			(at 235.585 80.01 0)
			(effects
				(font
					(size 1.27 1.27)
				)
				(justify left bottom)
				(hide yes)
			)
		)
		(property "Dielectric" "X5R"
			(at 233.045 80.01 0)
			(effects
				(font
					(size 1.27 1.27)
				)
				(justify left bottom)
				(hide yes)
			)
		)
		(pin "1"
		)
		(pin "2"
		)
		(instances
			(project "sodimm-ddr5-tester"
				(path ""
					(reference "C4")
					(unit 1)
				)
			)
		)
	)
	(symbol
		(lib_id "antmicropower:GND")
		(at 263.525 66.04 0)
		(unit 1)
		(exclude_from_sim no)
		(in_bom yes)
		(on_board yes)
		(dnp no)
		(fields_autoplaced yes)
		(property "Reference" "#PWR07"
			(at 263.525 72.39 0)
			(effects
				(font
					(size 1.27 1.27)
				)
				(hide yes)
			)
		)
		(property "Value" "GND"
			(at 265.43 67.31 0)
			(effects
				(font
					(size 1.27 1.27)
					(thickness 0.15)
				)
				(justify left)
			)
		)
		(property "Footprint" ""
			(at 272.415 73.66 0)
			(effects
				(font
					(size 1.27 1.27)
					(thickness 0.15)
				)
				(justify left bottom)
				(hide yes)
			)
		)
		(property "Datasheet" ""
			(at 272.415 78.74 0)
			(effects
				(font
					(size 1.27 1.27)
					(thickness 0.15)
				)
				(justify left bottom)
				(hide yes)
			)
		)
		(property "Description" ""
			(at 272.415 81.28 0)
			(effects
				(font
					(size 1.27 1.27)
				)
				(justify left bottom)
				(hide yes)
			)
		)
		(property "Author" "Antmicro"
			(at 272.415 73.66 0)
			(effects
				(font
					(size 1.27 1.27)
					(thickness 0.15)
				)
				(justify left bottom)
				(hide yes)
			)
		)
		(property "License" "Apache-2.0"
			(at 272.415 76.2 0)
			(effects
				(font
					(size 1.27 1.27)
					(thickness 0.15)
				)
				(justify left bottom)
				(hide yes)
			)
		)
		(pin "1"
		)
		(instances
			(project "sodimm-ddr5-tester"
				(path ""
					(reference "#PWR07")
					(unit 1)
				)
			)
		)
	)
	(symbol
		(lib_id "antmicroResistors0402:R_22R_0402")
		(at 237.49 208.28 0)
		(unit 1)
		(exclude_from_sim no)
		(in_bom yes)
		(on_board yes)
		(dnp no)
		(property "Reference" "R7"
			(at 243.84 207.01 0)
			(effects
				(font
					(size 1.27 1.27)
				)
			)
		)
		(property "Value" "R_22R_0402"
			(at 257.81 220.98 0)
			(effects
				(font
					(size 1.27 1.27)
					(thickness 0.15)
				)
				(justify left bottom)
				(hide yes)
			)
		)
		(property "Footprint" "antmicro-footprints:R_0402_1005Metric"
			(at 257.81 223.52 0)
			(effects
				(font
					(size 1.27 1.27)
					(thickness 0.15)
				)
				(justify left bottom)
				(hide yes)
			)
		)
		(property "Datasheet" "https://www.bourns.com/docs/product-datasheets/cr.pdf"
			(at 257.81 226.06 0)
			(effects
				(font
					(size 1.27 1.27)
					(thickness 0.15)
				)
				(justify left bottom)
				(hide yes)
			)
		)
		(property "Description" ""
			(at 237.49 208.28 0)
			(effects
				(font
					(size 1.27 1.27)
				)
			)
		)
		(property "Manufacturer" "Bourns"
			(at 257.81 231.14 0)
			(effects
				(font
					(size 1.27 1.27)
					(thickness 0.15)
				)
				(justify left bottom)
				(hide yes)
			)
		)
		(property "MPN" "CR0402-FX-22R0GLF"
			(at 257.81 228.6 0)
			(effects
				(font
					(size 1.27 1.27)
					(thickness 0.15)
				)
				(justify left bottom)
				(hide yes)
			)
		)
		(property "Val" "22R"
			(at 235.585 207.01 0)
			(effects
				(font
					(size 1.27 1.27)
					(thickness 0.15)
				)
			)
		)
		(property "License" "Apache-2.0"
			(at 257.81 233.68 0)
			(effects
				(font
					(size 1.27 1.27)
					(thickness 0.15)
				)
				(justify left bottom)
				(hide yes)
			)
		)
		(property "Author" "Antmicro"
			(at 257.81 236.22 0)
			(effects
				(font
					(size 1.27 1.27)
					(thickness 0.15)
				)
				(justify left bottom)
				(hide yes)
			)
		)
		(property "Tolerance" "1%"
			(at 257.81 218.44 0)
			(effects
				(font
					(size 1.27 1.27)
				)
				(justify left bottom)
				(hide yes)
			)
		)
		(pin "1"
		)
		(pin "2"
		)
		(instances
			(project "sodimm-ddr5-tester"
				(path ""
					(reference "R7")
					(unit 1)
				)
			)
		)
	)
	(symbol
		(lib_id "antmicroResistors0402:R_22R_0402")
		(at 237.49 210.82 0)
		(unit 1)
		(exclude_from_sim no)
		(in_bom yes)
		(on_board yes)
		(dnp no)
		(property "Reference" "R8"
			(at 243.84 209.55 0)
			(effects
				(font
					(size 1.27 1.27)
				)
			)
		)
		(property "Value" "R_22R_0402"
			(at 257.81 223.52 0)
			(effects
				(font
					(size 1.27 1.27)
					(thickness 0.15)
				)
				(justify left bottom)
				(hide yes)
			)
		)
		(property "Footprint" "antmicro-footprints:R_0402_1005Metric"
			(at 257.81 226.06 0)
			(effects
				(font
					(size 1.27 1.27)
					(thickness 0.15)
				)
				(justify left bottom)
				(hide yes)
			)
		)
		(property "Datasheet" "https://www.bourns.com/docs/product-datasheets/cr.pdf"
			(at 257.81 228.6 0)
			(effects
				(font
					(size 1.27 1.27)
					(thickness 0.15)
				)
				(justify left bottom)
				(hide yes)
			)
		)
		(property "Description" ""
			(at 237.49 210.82 0)
			(effects
				(font
					(size 1.27 1.27)
				)
			)
		)
		(property "Manufacturer" "Bourns"
			(at 257.81 233.68 0)
			(effects
				(font
					(size 1.27 1.27)
					(thickness 0.15)
				)
				(justify left bottom)
				(hide yes)
			)
		)
		(property "MPN" "CR0402-FX-22R0GLF"
			(at 257.81 231.14 0)
			(effects
				(font
					(size 1.27 1.27)
					(thickness 0.15)
				)
				(justify left bottom)
				(hide yes)
			)
		)
		(property "Val" "22R"
			(at 235.585 209.55 0)
			(effects
				(font
					(size 1.27 1.27)
					(thickness 0.15)
				)
			)
		)
		(property "License" "Apache-2.0"
			(at 257.81 236.22 0)
			(effects
				(font
					(size 1.27 1.27)
					(thickness 0.15)
				)
				(justify left bottom)
				(hide yes)
			)
		)
		(property "Author" "Antmicro"
			(at 257.81 238.76 0)
			(effects
				(font
					(size 1.27 1.27)
					(thickness 0.15)
				)
				(justify left bottom)
				(hide yes)
			)
		)
		(property "Tolerance" "1%"
			(at 257.81 220.98 0)
			(effects
				(font
					(size 1.27 1.27)
				)
				(justify left bottom)
				(hide yes)
			)
		)
		(pin "1"
		)
		(pin "2"
		)
		(instances
			(project "sodimm-ddr5-tester"
				(path ""
					(reference "R8")
					(unit 1)
				)
			)
		)
	)
	(symbol
		(lib_id "antmicroResistors0402:R_4k7_0402")
		(at 227.33 194.945 90)
		(mirror x)
		(unit 1)
		(exclude_from_sim no)
		(in_bom yes)
		(on_board yes)
		(dnp no)
		(property "Reference" "R5"
			(at 227.33 194.31 90)
			(effects
				(font
					(size 1.27 1.27)
				)
				(justify right)
			)
		)
		(property "Value" "R_4k7_0402"
			(at 240.03 215.265 0)
			(effects
				(font
					(size 1.27 1.27)
					(thickness 0.15)
				)
				(justify left bottom)
				(hide yes)
			)
		)
		(property "Footprint" "antmicro-footprints:R_0402_1005Metric"
			(at 242.57 215.265 0)
			(effects
				(font
					(size 1.27 1.27)
					(thickness 0.15)
				)
				(justify left bottom)
				(hide yes)
			)
		)
		(property "Datasheet" "https://www.bourns.com/docs/product-datasheets/cr.pdf"
			(at 245.11 215.265 0)
			(effects
				(font
					(size 1.27 1.27)
					(thickness 0.15)
				)
				(justify left bottom)
				(hide yes)
			)
		)
		(property "Description" ""
			(at 227.33 194.945 0)
			(effects
				(font
					(size 1.27 1.27)
				)
			)
		)
		(property "Manufacturer" "Bourns"
			(at 250.19 215.265 0)
			(effects
				(font
					(size 1.27 1.27)
					(thickness 0.15)
				)
				(justify left bottom)
				(hide yes)
			)
		)
		(property "MPN" "CR0402-FX-4701GLF"
			(at 247.65 215.265 0)
			(effects
				(font
					(size 1.27 1.27)
					(thickness 0.15)
				)
				(justify left bottom)
				(hide yes)
			)
		)
		(property "Val" "4k7"
			(at 229.235 199.39 90)
			(effects
				(font
					(size 1.27 1.27)
					(thickness 0.15)
				)
				(justify right)
			)
		)
		(property "License" "Apache-2.0"
			(at 252.73 215.265 0)
			(effects
				(font
					(size 1.27 1.27)
					(thickness 0.15)
				)
				(justify left bottom)
				(hide yes)
			)
		)
		(property "Author" "Antmicro"
			(at 255.27 215.265 0)
			(effects
				(font
					(size 1.27 1.27)
					(thickness 0.15)
				)
				(justify left bottom)
				(hide yes)
			)
		)
		(property "Tolerance" "1%"
			(at 237.49 215.265 0)
			(effects
				(font
					(size 1.27 1.27)
				)
				(justify left bottom)
				(hide yes)
			)
		)
		(pin "1"
		)
		(pin "2"
		)
		(instances
			(project "sodimm-ddr5-tester"
				(path ""
					(reference "R5")
					(unit 1)
				)
			)
		)
	)
	(symbol
		(lib_id "antmicroResistors0402:R_22R_0402")
		(at 237.49 213.36 0)
		(unit 1)
		(exclude_from_sim no)
		(in_bom yes)
		(on_board yes)
		(dnp no)
		(property "Reference" "R9"
			(at 243.84 212.09 0)
			(effects
				(font
					(size 1.27 1.27)
				)
			)
		)
		(property "Value" "R_22R_0402"
			(at 257.81 226.06 0)
			(effects
				(font
					(size 1.27 1.27)
					(thickness 0.15)
				)
				(justify left bottom)
				(hide yes)
			)
		)
		(property "Footprint" "antmicro-footprints:R_0402_1005Metric"
			(at 257.81 228.6 0)
			(effects
				(font
					(size 1.27 1.27)
					(thickness 0.15)
				)
				(justify left bottom)
				(hide yes)
			)
		)
		(property "Datasheet" "https://www.bourns.com/docs/product-datasheets/cr.pdf"
			(at 257.81 231.14 0)
			(effects
				(font
					(size 1.27 1.27)
					(thickness 0.15)
				)
				(justify left bottom)
				(hide yes)
			)
		)
		(property "Description" ""
			(at 237.49 213.36 0)
			(effects
				(font
					(size 1.27 1.27)
				)
			)
		)
		(property "Manufacturer" "Bourns"
			(at 257.81 236.22 0)
			(effects
				(font
					(size 1.27 1.27)
					(thickness 0.15)
				)
				(justify left bottom)
				(hide yes)
			)
		)
		(property "MPN" "CR0402-FX-22R0GLF"
			(at 257.81 233.68 0)
			(effects
				(font
					(size 1.27 1.27)
					(thickness 0.15)
				)
				(justify left bottom)
				(hide yes)
			)
		)
		(property "Val" "22R"
			(at 235.585 212.09 0)
			(effects
				(font
					(size 1.27 1.27)
					(thickness 0.15)
				)
			)
		)
		(property "License" "Apache-2.0"
			(at 257.81 238.76 0)
			(effects
				(font
					(size 1.27 1.27)
					(thickness 0.15)
				)
				(justify left bottom)
				(hide yes)
			)
		)
		(property "Author" "Antmicro"
			(at 257.81 241.3 0)
			(effects
				(font
					(size 1.27 1.27)
					(thickness 0.15)
				)
				(justify left bottom)
				(hide yes)
			)
		)
		(property "Tolerance" "1%"
			(at 257.81 223.52 0)
			(effects
				(font
					(size 1.27 1.27)
				)
				(justify left bottom)
				(hide yes)
			)
		)
		(pin "1"
		)
		(pin "2"
		)
		(instances
			(project "sodimm-ddr5-tester"
				(path ""
					(reference "R9")
					(unit 1)
				)
			)
		)
	)
	(symbol
		(lib_id "antmicroCapacitors0402:C_100n_0402")
		(at 170.18 209.55 90)
		(mirror x)
		(unit 1)
		(exclude_from_sim no)
		(in_bom yes)
		(on_board yes)
		(dnp no)
		(fields_autoplaced yes)
		(property "Reference" "C5"
			(at 172.72 210.8263 90)
			(effects
				(font
					(size 1.27 1.27)
				)
				(justify right)
			)
		)
		(property "Value" "C_100n_0402"
			(at 180.34 229.87 0)
			(effects
				(font
					(size 1.27 1.27)
					(thickness 0.15)
				)
				(justify left bottom)
				(hide yes)
			)
		)
		(property "Footprint" "antmicro-footprints:C_0402_1005Metric"
			(at 182.88 229.87 0)
			(effects
				(font
					(size 1.27 1.27)
					(thickness 0.15)
				)
				(justify left bottom)
				(hide yes)
			)
		)
		(property "Datasheet" "https://www.murata.com/products/productdetail?partno=GRM155R61H104KE14%23"
			(at 185.42 229.87 0)
			(effects
				(font
					(size 1.27 1.27)
					(thickness 0.15)
				)
				(justify left bottom)
				(hide yes)
			)
		)
		(property "Description" ""
			(at 170.18 209.55 0)
			(effects
				(font
					(size 1.27 1.27)
				)
			)
		)
		(property "Manufacturer" "Murata"
			(at 190.5 229.87 0)
			(effects
				(font
					(size 1.27 1.27)
					(thickness 0.15)
				)
				(justify left bottom)
				(hide yes)
			)
		)
		(property "MPN" "GRM155R61H104KE14D"
			(at 187.96 229.87 0)
			(effects
				(font
					(size 1.27 1.27)
					(thickness 0.15)
				)
				(justify left bottom)
				(hide yes)
			)
		)
		(property "Val" "100n"
			(at 172.72 214.0012 90)
			(effects
				(font
					(size 1.27 1.27)
					(thickness 0.15)
				)
				(justify right)
			)
		)
		(property "License" "Apache-2.0"
			(at 193.04 229.87 0)
			(effects
				(font
					(size 1.27 1.27)
					(thickness 0.15)
				)
				(justify left bottom)
				(hide yes)
			)
		)
		(property "Author" "Antmicro"
			(at 195.58 229.87 0)
			(effects
				(font
					(size 1.27 1.27)
					(thickness 0.15)
				)
				(justify left bottom)
				(hide yes)
			)
		)
		(property "Voltage" "50V"
			(at 198.12 229.87 0)
			(effects
				(font
					(size 1.27 1.27)
				)
				(justify left bottom)
				(hide yes)
			)
		)
		(property "Dielectric" "X5R"
			(at 200.66 229.87 0)
			(effects
				(font
					(size 1.27 1.27)
				)
				(justify left bottom)
				(hide yes)
			)
		)
		(pin "1"
		)
		(pin "2"
		)
		(instances
			(project "sodimm-ddr5-tester"
				(path ""
					(reference "C5")
					(unit 1)
				)
			)
		)
	)
	(symbol
		(lib_id "antmicropower:GND")
		(at 247.65 226.695 0)
		(unit 1)
		(exclude_from_sim no)
		(in_bom yes)
		(on_board yes)
		(dnp no)
		(fields_autoplaced yes)
		(property "Reference" "#PWR0172"
			(at 247.65 233.045 0)
			(effects
				(font
					(size 1.27 1.27)
				)
				(hide yes)
			)
		)
		(property "Value" "GND"
			(at 250.19 227.965 0)
			(effects
				(font
					(size 1.27 1.27)
					(thickness 0.15)
				)
				(justify left)
			)
		)
		(property "Footprint" ""
			(at 256.54 234.315 0)
			(effects
				(font
					(size 1.27 1.27)
					(thickness 0.15)
				)
				(justify left bottom)
				(hide yes)
			)
		)
		(property "Datasheet" ""
			(at 256.54 239.395 0)
			(effects
				(font
					(size 1.27 1.27)
					(thickness 0.15)
				)
				(justify left bottom)
				(hide yes)
			)
		)
		(property "Description" ""
			(at 256.54 241.935 0)
			(effects
				(font
					(size 1.27 1.27)
				)
				(justify left bottom)
				(hide yes)
			)
		)
		(property "Author" "Antmicro"
			(at 256.54 234.315 0)
			(effects
				(font
					(size 1.27 1.27)
					(thickness 0.15)
				)
				(justify left bottom)
				(hide yes)
			)
		)
		(property "License" "Apache-2.0"
			(at 256.54 236.855 0)
			(effects
				(font
					(size 1.27 1.27)
					(thickness 0.15)
				)
				(justify left bottom)
				(hide yes)
			)
		)
		(pin "1"
		)
		(instances
			(project "sodimm-ddr5-tester"
				(path ""
					(reference "#PWR0172")
					(unit 1)
				)
			)
		)
	)
	(symbol
		(lib_id "antmicroResistors0402:R_2k2_0402")
		(at 210.82 194.945 270)
		(unit 1)
		(exclude_from_sim no)
		(in_bom yes)
		(on_board yes)
		(dnp no)
		(property "Reference" "R3"
			(at 210.82 194.3099 90)
			(effects
				(font
					(size 1.27 1.27)
				)
				(justify left)
			)
		)
		(property "Value" "R_2k2_0402"
			(at 198.12 215.265 0)
			(effects
				(font
					(size 1.27 1.27)
					(thickness 0.15)
				)
				(justify left bottom)
				(hide yes)
			)
		)
		(property "Footprint" "antmicro-footprints:R_0402_1005Metric"
			(at 195.58 215.265 0)
			(effects
				(font
					(size 1.27 1.27)
					(thickness 0.15)
				)
				(justify left bottom)
				(hide yes)
			)
		)
		(property "Datasheet" "https://www.bourns.com/docs/product-datasheets/cr.pdf"
			(at 193.04 215.265 0)
			(effects
				(font
					(size 1.27 1.27)
					(thickness 0.15)
				)
				(justify left bottom)
				(hide yes)
			)
		)
		(property "Description" ""
			(at 210.82 194.945 0)
			(effects
				(font
					(size 1.27 1.27)
				)
			)
		)
		(property "Manufacturer" "Bourns"
			(at 187.96 215.265 0)
			(effects
				(font
					(size 1.27 1.27)
					(thickness 0.15)
				)
				(justify left bottom)
				(hide yes)
			)
		)
		(property "MPN" "CR0402-FX-2201GLF"
			(at 190.5 215.265 0)
			(effects
				(font
					(size 1.27 1.27)
					(thickness 0.15)
				)
				(justify left bottom)
				(hide yes)
			)
		)
		(property "Val" "2k2"
			(at 212.725 199.3899 90)
			(effects
				(font
					(size 1.27 1.27)
					(thickness 0.15)
				)
				(justify left)
			)
		)
		(property "License" "Apache-2.0"
			(at 185.42 215.265 0)
			(effects
				(font
					(size 1.27 1.27)
					(thickness 0.15)
				)
				(justify left bottom)
				(hide yes)
			)
		)
		(property "Author" "Antmicro"
			(at 182.88 215.265 0)
			(effects
				(font
					(size 1.27 1.27)
					(thickness 0.15)
				)
				(justify left bottom)
				(hide yes)
			)
		)
		(property "Tolerance" "1%"
			(at 200.66 215.265 0)
			(effects
				(font
					(size 1.27 1.27)
				)
				(justify left bottom)
				(hide yes)
			)
		)
		(pin "1"
		)
		(pin "2"
		)
		(instances
			(project "sodimm-ddr5-tester"
				(path ""
					(reference "R3")
					(unit 1)
				)
			)
		)
	)
	(symbol
		(lib_id "antmicroResistors0402:R_4k7_0402")
		(at 219.075 194.945 90)
		(mirror x)
		(unit 1)
		(exclude_from_sim no)
		(in_bom yes)
		(on_board yes)
		(dnp no)
		(property "Reference" "R4"
			(at 219.075 194.3099 90)
			(effects
				(font
					(size 1.27 1.27)
				)
				(justify right)
			)
		)
		(property "Value" "R_4k7_0402"
			(at 231.775 215.265 0)
			(effects
				(font
					(size 1.27 1.27)
					(thickness 0.15)
				)
				(justify left bottom)
				(hide yes)
			)
		)
		(property "Footprint" "antmicro-footprints:R_0402_1005Metric"
			(at 234.315 215.265 0)
			(effects
				(font
					(size 1.27 1.27)
					(thickness 0.15)
				)
				(justify left bottom)
				(hide yes)
			)
		)
		(property "Datasheet" "https://www.bourns.com/docs/product-datasheets/cr.pdf"
			(at 236.855 215.265 0)
			(effects
				(font
					(size 1.27 1.27)
					(thickness 0.15)
				)
				(justify left bottom)
				(hide yes)
			)
		)
		(property "Description" ""
			(at 219.075 194.945 0)
			(effects
				(font
					(size 1.27 1.27)
				)
			)
		)
		(property "Manufacturer" "Bourns"
			(at 241.935 215.265 0)
			(effects
				(font
					(size 1.27 1.27)
					(thickness 0.15)
				)
				(justify left bottom)
				(hide yes)
			)
		)
		(property "MPN" "CR0402-FX-4701GLF"
			(at 239.395 215.265 0)
			(effects
				(font
					(size 1.27 1.27)
					(thickness 0.15)
				)
				(justify left bottom)
				(hide yes)
			)
		)
		(property "Val" "4k7"
			(at 220.98 199.3899 90)
			(effects
				(font
					(size 1.27 1.27)
					(thickness 0.15)
				)
				(justify right)
			)
		)
		(property "License" "Apache-2.0"
			(at 244.475 215.265 0)
			(effects
				(font
					(size 1.27 1.27)
					(thickness 0.15)
				)
				(justify left bottom)
				(hide yes)
			)
		)
		(property "Author" "Antmicro"
			(at 247.015 215.265 0)
			(effects
				(font
					(size 1.27 1.27)
					(thickness 0.15)
				)
				(justify left bottom)
				(hide yes)
			)
		)
		(property "Tolerance" "1%"
			(at 229.235 215.265 0)
			(effects
				(font
					(size 1.27 1.27)
				)
				(justify left bottom)
				(hide yes)
			)
		)
		(pin "1"
		)
		(pin "2"
		)
		(instances
			(project "sodimm-ddr5-tester"
				(path ""
					(reference "R4")
					(unit 1)
				)
			)
		)
	)
	(symbol
		(lib_id "antmicropower:+3V3")
		(at 210.82 189.865 0)
		(unit 1)
		(exclude_from_sim no)
		(in_bom yes)
		(on_board yes)
		(dnp no)
		(property "Reference" "#PWR0173"
			(at 210.82 193.675 0)
			(effects
				(font
					(size 1.27 1.27)
				)
				(hide yes)
			)
		)
		(property "Value" "+3V3"
			(at 207.645 187.325 0)
			(effects
				(font
					(size 1.27 1.27)
					(thickness 0.15)
				)
				(justify left bottom)
			)
		)
		(property "Footprint" ""
			(at 226.06 197.485 0)
			(effects
				(font
					(size 1.27 1.27)
					(thickness 0.15)
				)
				(justify left bottom)
				(hide yes)
			)
		)
		(property "Datasheet" ""
			(at 226.06 200.025 0)
			(effects
				(font
					(size 1.27 1.27)
					(thickness 0.15)
				)
				(justify left bottom)
				(hide yes)
			)
		)
		(property "Description" ""
			(at 210.82 189.865 0)
			(effects
				(font
					(size 1.27 1.27)
				)
			)
		)
		(property "Author" "Antmicro"
			(at 226.06 192.405 0)
			(effects
				(font
					(size 1.27 1.27)
					(thickness 0.15)
				)
				(justify left bottom)
				(hide yes)
			)
		)
		(property "License" "Apache-2.0"
			(at 226.06 194.945 0)
			(effects
				(font
					(size 1.27 1.27)
					(thickness 0.15)
				)
				(justify left bottom)
				(hide yes)
			)
		)
		(pin "1"
		)
		(instances
			(project "sodimm-ddr5-tester"
				(path ""
					(reference "#PWR0173")
					(unit 1)
				)
			)
		)
	)
	(symbol
		(lib_id "antmicroResistors0402:R_22R_0402")
		(at 237.49 205.74 0)
		(unit 1)
		(exclude_from_sim no)
		(in_bom yes)
		(on_board yes)
		(dnp no)
		(property "Reference" "R6"
			(at 243.84 204.47 0)
			(effects
				(font
					(size 1.27 1.27)
				)
			)
		)
		(property "Value" "R_22R_0402"
			(at 257.81 218.44 0)
			(effects
				(font
					(size 1.27 1.27)
					(thickness 0.15)
				)
				(justify left bottom)
				(hide yes)
			)
		)
		(property "Footprint" "antmicro-footprints:R_0402_1005Metric"
			(at 257.81 220.98 0)
			(effects
				(font
					(size 1.27 1.27)
					(thickness 0.15)
				)
				(justify left bottom)
				(hide yes)
			)
		)
		(property "Datasheet" "https://www.bourns.com/docs/product-datasheets/cr.pdf"
			(at 257.81 223.52 0)
			(effects
				(font
					(size 1.27 1.27)
					(thickness 0.15)
				)
				(justify left bottom)
				(hide yes)
			)
		)
		(property "Description" ""
			(at 237.49 205.74 0)
			(effects
				(font
					(size 1.27 1.27)
				)
			)
		)
		(property "Manufacturer" "Bourns"
			(at 257.81 228.6 0)
			(effects
				(font
					(size 1.27 1.27)
					(thickness 0.15)
				)
				(justify left bottom)
				(hide yes)
			)
		)
		(property "MPN" "CR0402-FX-22R0GLF"
			(at 257.81 226.06 0)
			(effects
				(font
					(size 1.27 1.27)
					(thickness 0.15)
				)
				(justify left bottom)
				(hide yes)
			)
		)
		(property "Val" "22R"
			(at 235.585 204.47 0)
			(effects
				(font
					(size 1.27 1.27)
					(thickness 0.15)
				)
			)
		)
		(property "License" "Apache-2.0"
			(at 257.81 231.14 0)
			(effects
				(font
					(size 1.27 1.27)
					(thickness 0.15)
				)
				(justify left bottom)
				(hide yes)
			)
		)
		(property "Author" "Antmicro"
			(at 257.81 233.68 0)
			(effects
				(font
					(size 1.27 1.27)
					(thickness 0.15)
				)
				(justify left bottom)
				(hide yes)
			)
		)
		(property "Tolerance" "1%"
			(at 257.81 215.9 0)
			(effects
				(font
					(size 1.27 1.27)
				)
				(justify left bottom)
				(hide yes)
			)
		)
		(pin "1"
		)
		(pin "2"
		)
		(instances
			(project "sodimm-ddr5-tester"
				(path ""
					(reference "R6")
					(unit 1)
				)
			)
		)
	)
	(symbol
		(lib_id "antmicropower:GND")
		(at 178.435 219.71 0)
		(unit 1)
		(exclude_from_sim no)
		(in_bom yes)
		(on_board yes)
		(dnp no)
		(fields_autoplaced yes)
		(property "Reference" "#PWR0169"
			(at 178.435 226.06 0)
			(effects
				(font
					(size 1.27 1.27)
				)
				(hide yes)
			)
		)
		(property "Value" "GND"
			(at 180.34 220.98 0)
			(effects
				(font
					(size 1.27 1.27)
					(thickness 0.15)
				)
				(justify left)
			)
		)
		(property "Footprint" ""
			(at 187.325 227.33 0)
			(effects
				(font
					(size 1.27 1.27)
					(thickness 0.15)
				)
				(justify left bottom)
				(hide yes)
			)
		)
		(property "Datasheet" ""
			(at 187.325 232.41 0)
			(effects
				(font
					(size 1.27 1.27)
					(thickness 0.15)
				)
				(justify left bottom)
				(hide yes)
			)
		)
		(property "Description" ""
			(at 187.325 234.95 0)
			(effects
				(font
					(size 1.27 1.27)
				)
				(justify left bottom)
				(hide yes)
			)
		)
		(property "Author" "Antmicro"
			(at 187.325 227.33 0)
			(effects
				(font
					(size 1.27 1.27)
					(thickness 0.15)
				)
				(justify left bottom)
				(hide yes)
			)
		)
		(property "License" "Apache-2.0"
			(at 187.325 229.87 0)
			(effects
				(font
					(size 1.27 1.27)
					(thickness 0.15)
				)
				(justify left bottom)
				(hide yes)
			)
		)
		(pin "1"
		)
		(instances
			(project "sodimm-ddr5-tester"
				(path ""
					(reference "#PWR0169")
					(unit 1)
				)
			)
		)
	)
	(symbol
		(lib_id "antmicropower:+3V3")
		(at 191.77 45.72 0)
		(unit 1)
		(exclude_from_sim no)
		(in_bom yes)
		(on_board yes)
		(dnp no)
		(fields_autoplaced yes)
		(property "Reference" "#PWR01"
			(at 191.77 49.53 0)
			(effects
				(font
					(size 1.27 1.27)
				)
				(hide yes)
			)
		)
		(property "Value" "+3V3"
			(at 188.595 43.18 0)
			(effects
				(font
					(size 1.27 1.27)
					(thickness 0.15)
				)
				(justify left bottom)
			)
		)
		(property "Footprint" ""
			(at 207.01 53.34 0)
			(effects
				(font
					(size 1.27 1.27)
					(thickness 0.15)
				)
				(justify left bottom)
				(hide yes)
			)
		)
		(property "Datasheet" ""
			(at 207.01 55.88 0)
			(effects
				(font
					(size 1.27 1.27)
					(thickness 0.15)
				)
				(justify left bottom)
				(hide yes)
			)
		)
		(property "Description" ""
			(at 191.77 45.72 0)
			(effects
				(font
					(size 1.27 1.27)
				)
			)
		)
		(property "Author" "Antmicro"
			(at 207.01 48.26 0)
			(effects
				(font
					(size 1.27 1.27)
					(thickness 0.15)
				)
				(justify left bottom)
				(hide yes)
			)
		)
		(property "License" "Apache-2.0"
			(at 207.01 50.8 0)
			(effects
				(font
					(size 1.27 1.27)
					(thickness 0.15)
				)
				(justify left bottom)
				(hide yes)
			)
		)
		(pin "1"
		)
		(instances
			(project "sodimm-ddr5-tester"
				(path ""
					(reference "#PWR01")
					(unit 1)
				)
			)
		)
	)
	(symbol
		(lib_id "antmicropower:+3V3")
		(at 170.18 205.105 0)
		(unit 1)
		(exclude_from_sim no)
		(in_bom yes)
		(on_board yes)
		(dnp no)
		(property "Reference" "#PWR0170"
			(at 170.18 208.915 0)
			(effects
				(font
					(size 1.27 1.27)
				)
				(hide yes)
			)
		)
		(property "Value" "+3V3"
			(at 167.005 202.565 0)
			(effects
				(font
					(size 1.27 1.27)
					(thickness 0.15)
				)
				(justify left bottom)
			)
		)
		(property "Footprint" ""
			(at 185.42 212.725 0)
			(effects
				(font
					(size 1.27 1.27)
					(thickness 0.15)
				)
				(justify left bottom)
				(hide yes)
			)
		)
		(property "Datasheet" ""
			(at 185.42 215.265 0)
			(effects
				(font
					(size 1.27 1.27)
					(thickness 0.15)
				)
				(justify left bottom)
				(hide yes)
			)
		)
		(property "Description" ""
			(at 170.18 205.105 0)
			(effects
				(font
					(size 1.27 1.27)
				)
			)
		)
		(property "Author" "Antmicro"
			(at 185.42 207.645 0)
			(effects
				(font
					(size 1.27 1.27)
					(thickness 0.15)
				)
				(justify left bottom)
				(hide yes)
			)
		)
		(property "License" "Apache-2.0"
			(at 185.42 210.185 0)
			(effects
				(font
					(size 1.27 1.27)
					(thickness 0.15)
				)
				(justify left bottom)
				(hide yes)
			)
		)
		(pin "1"
		)
		(instances
			(project "sodimm-ddr5-tester"
				(path ""
					(reference "#PWR0170")
					(unit 1)
				)
			)
		)
	)
	(symbol
		(lib_id "antmicropower:+3V3")
		(at 263.525 55.88 0)
		(unit 1)
		(exclude_from_sim no)
		(in_bom yes)
		(on_board yes)
		(dnp no)
		(fields_autoplaced yes)
		(property "Reference" "#PWR02"
			(at 263.525 59.69 0)
			(effects
				(font
					(size 1.27 1.27)
				)
				(hide yes)
			)
		)
		(property "Value" "+3V3"
			(at 260.35 53.34 0)
			(effects
				(font
					(size 1.27 1.27)
					(thickness 0.15)
				)
				(justify left bottom)
			)
		)
		(property "Footprint" ""
			(at 278.765 63.5 0)
			(effects
				(font
					(size 1.27 1.27)
					(thickness 0.15)
				)
				(justify left bottom)
				(hide yes)
			)
		)
		(property "Datasheet" ""
			(at 278.765 66.04 0)
			(effects
				(font
					(size 1.27 1.27)
					(thickness 0.15)
				)
				(justify left bottom)
				(hide yes)
			)
		)
		(property "Description" ""
			(at 263.525 55.88 0)
			(effects
				(font
					(size 1.27 1.27)
				)
			)
		)
		(property "Author" "Antmicro"
			(at 278.765 58.42 0)
			(effects
				(font
					(size 1.27 1.27)
					(thickness 0.15)
				)
				(justify left bottom)
				(hide yes)
			)
		)
		(property "License" "Apache-2.0"
			(at 278.765 60.96 0)
			(effects
				(font
					(size 1.27 1.27)
					(thickness 0.15)
				)
				(justify left bottom)
				(hide yes)
			)
		)
		(pin "1"
		)
		(instances
			(project "sodimm-ddr5-tester"
				(path ""
					(reference "#PWR02")
					(unit 1)
				)
			)
		)
	)
	(symbol
		(lib_id "antmicropower:GND")
		(at 170.18 219.71 0)
		(unit 1)
		(exclude_from_sim no)
		(in_bom yes)
		(on_board yes)
		(dnp no)
		(fields_autoplaced yes)
		(property "Reference" "#PWR0171"
			(at 170.18 226.06 0)
			(effects
				(font
					(size 1.27 1.27)
				)
				(hide yes)
			)
		)
		(property "Value" "GND"
			(at 172.72 220.98 0)
			(effects
				(font
					(size 1.27 1.27)
					(thickness 0.15)
				)
				(justify left)
			)
		)
		(property "Footprint" ""
			(at 179.07 227.33 0)
			(effects
				(font
					(size 1.27 1.27)
					(thickness 0.15)
				)
				(justify left bottom)
				(hide yes)
			)
		)
		(property "Datasheet" ""
			(at 179.07 232.41 0)
			(effects
				(font
					(size 1.27 1.27)
					(thickness 0.15)
				)
				(justify left bottom)
				(hide yes)
			)
		)
		(property "Description" ""
			(at 179.07 234.95 0)
			(effects
				(font
					(size 1.27 1.27)
				)
				(justify left bottom)
				(hide yes)
			)
		)
		(property "Author" "Antmicro"
			(at 179.07 227.33 0)
			(effects
				(font
					(size 1.27 1.27)
					(thickness 0.15)
				)
				(justify left bottom)
				(hide yes)
			)
		)
		(property "License" "Apache-2.0"
			(at 179.07 229.87 0)
			(effects
				(font
					(size 1.27 1.27)
					(thickness 0.15)
				)
				(justify left bottom)
				(hide yes)
			)
		)
		(pin "1"
		)
		(instances
			(project "sodimm-ddr5-tester"
				(path ""
					(reference "#PWR0171")
					(unit 1)
				)
			)
		)
	)
	(symbol
		(lib_id "antmicroResistors0402:R_100R_0402")
		(at 247.65 221.615 270)
		(unit 1)
		(exclude_from_sim no)
		(in_bom no)
		(on_board yes)
		(dnp yes)
		(property "Reference" "R10"
			(at 250.19 222.885 90)
			(effects
				(font
					(size 1.27 1.27)
				)
				(justify left)
			)
		)
		(property "Value" "R_100R_0402"
			(at 234.95 241.935 0)
			(effects
				(font
					(size 1.27 1.27)
					(thickness 0.15)
				)
				(justify left bottom)
				(hide yes)
			)
		)
		(property "Footprint" "antmicro-footprints:R_0402_1005Metric"
			(at 232.41 241.935 0)
			(effects
				(font
					(size 1.27 1.27)
					(thickness 0.15)
				)
				(justify left bottom)
				(hide yes)
			)
		)
		(property "Datasheet" "https://www.bourns.com/docs/product-datasheets/cr.pdf"
			(at 229.87 241.935 0)
			(effects
				(font
					(size 1.27 1.27)
					(thickness 0.15)
				)
				(justify left bottom)
				(hide yes)
			)
		)
		(property "Description" ""
			(at 247.65 221.615 0)
			(effects
				(font
					(size 1.27 1.27)
				)
			)
		)
		(property "Manufacturer" "Bourns"
			(at 224.79 241.935 0)
			(effects
				(font
					(size 1.27 1.27)
					(thickness 0.15)
				)
				(justify left bottom)
				(hide yes)
			)
		)
		(property "MPN" "CR0402-FX-1000GLF"
			(at 227.33 241.935 0)
			(effects
				(font
					(size 1.27 1.27)
					(thickness 0.15)
				)
				(justify left bottom)
				(hide yes)
			)
		)
		(property "Val" "100R"
			(at 250.19 226.0599 90)
			(effects
				(font
					(size 1.27 1.27)
					(thickness 0.15)
				)
				(justify left)
			)
		)
		(property "License" "Apache-2.0"
			(at 222.25 241.935 0)
			(effects
				(font
					(size 1.27 1.27)
					(thickness 0.15)
				)
				(justify left bottom)
				(hide yes)
			)
		)
		(property "Author" "Antmicro"
			(at 219.71 241.935 0)
			(effects
				(font
					(size 1.27 1.27)
					(thickness 0.15)
				)
				(justify left bottom)
				(hide yes)
			)
		)
		(property "Tolerance" "1%"
			(at 237.49 241.935 0)
			(effects
				(font
					(size 1.27 1.27)
				)
				(justify left bottom)
				(hide yes)
			)
		)
		(pin "1"
		)
		(pin "2"
		)
		(instances
			(project "sodimm-ddr5-tester"
				(path ""
					(reference "R10")
					(unit 1)
				)
			)
		)
	)
	(symbol
		(lib_id "antmicroMemory:S25FL128SAGNFI000")
		(at 200.025 203.2 0)
		(mirror y)
		(unit 1)
		(exclude_from_sim no)
		(in_bom yes)
		(on_board yes)
		(dnp no)
		(fields_autoplaced yes)
		(property "Reference" "U3"
			(at 189.865 199.5084 0)
			(effects
				(font
					(size 1.27 1.27)
				)
			)
		)
		(property "Value" "S25FL128SAGNFI000"
			(at 189.865 202.0387 0)
			(effects
				(font
					(size 1.27 1.27)
					(thickness 0.15)
				)
			)
		)
		(property "Footprint" "antmicro-footprints:WSON-8_6x8x0.5mm_P1.27mm"
			(at 154.305 210.82 0)
			(effects
				(font
					(size 1.27 1.27)
					(thickness 0.15)
				)
				(justify left bottom)
				(hide yes)
			)
		)
		(property "Datasheet" "https://www.farnell.com/datasheets/2309615.pdf"
			(at 154.305 213.36 0)
			(effects
				(font
					(size 1.27 1.27)
					(thickness 0.15)
				)
				(justify left bottom)
				(hide yes)
			)
		)
		(property "Description" ""
			(at 200.025 203.2 0)
			(effects
				(font
					(size 1.27 1.27)
				)
			)
		)
		(property "MPN" "S25FL128SAGNFI000"
			(at 154.305 218.44 0)
			(effects
				(font
					(size 1.27 1.27)
					(thickness 0.15)
				)
				(justify left bottom)
				(hide yes)
			)
		)
		(property "Manufacturer" "Cypress Semiconductor"
			(at 154.305 215.9 0)
			(effects
				(font
					(size 1.27 1.27)
					(thickness 0.15)
				)
				(justify left bottom)
				(hide yes)
			)
		)
		(property "Author" "Antmicro"
			(at 154.305 220.98 0)
			(effects
				(font
					(size 1.27 1.27)
					(thickness 0.15)
				)
				(justify left bottom)
				(hide yes)
			)
		)
		(property "License" "Apache-2.0"
			(at 154.305 223.52 0)
			(effects
				(font
					(size 1.27 1.27)
					(thickness 0.15)
				)
				(justify left bottom)
				(hide yes)
			)
		)
		(pin "1"
		)
		(pin "2"
		)
		(pin "3"
		)
		(pin "4"
		)
		(pin "5"
		)
		(pin "6"
		)
		(pin "7"
		)
		(pin "8"
		)
		(pin "9"
		)
		(instances
			(project "sodimm-ddr5-tester"
				(path ""
					(reference "U3")
					(unit 1)
				)
			)
		)
	)
	(symbol
		(lib_id "antmicroMemory:IS66WVH16M8DBLL-100B1LI")
		(at 200.66 57.15 0)
		(unit 1)
		(exclude_from_sim no)
		(in_bom yes)
		(on_board yes)
		(dnp no)
		(fields_autoplaced yes)
		(property "Reference" "U1"
			(at 215.9 50.925 0)
			(effects
				(font
					(size 1.27 1.27)
					(thickness 0.15)
				)
			)
		)
		(property "Value" "IS66WVH16M8DBLL-100B1LI"
			(at 215.9 53.4487 0)
			(effects
				(font
					(size 1.27 1.27)
					(thickness 0.15)
				)
				(hide yes)
			)
		)
		(property "Footprint" "antmicro-footprints:FBGA-25-24_6x8mm_Layout5x5_P1mm"
			(at 246.38 67.31 0)
			(effects
				(font
					(size 1.27 1.27)
					(thickness 0.15)
				)
				(justify left bottom)
				(hide yes)
			)
		)
		(property "Datasheet" "https://eu.mouser.com/datasheet/2/198/issi_s_a0011529618_1-2271553.pdf"
			(at 246.38 69.85 0)
			(effects
				(font
					(size 1.27 1.27)
					(thickness 0.15)
				)
				(justify left bottom)
				(hide yes)
			)
		)
		(property "Description" ""
			(at 200.66 57.15 0)
			(effects
				(font
					(size 1.27 1.27)
				)
			)
		)
		(property "Manufacturer" "ISSI"
			(at 246.38 72.39 0)
			(effects
				(font
					(size 1.27 1.27)
					(thickness 0.15)
				)
				(justify left bottom)
				(hide yes)
			)
		)
		(property "MPN" "IS66WVH16M8DBLL-100B1LI"
			(at 215.9 53.4487 0)
			(effects
				(font
					(size 1.27 1.27)
					(thickness 0.15)
				)
			)
		)
		(property "Author" "Antmicro"
			(at 246.38 77.47 0)
			(effects
				(font
					(size 1.27 1.27)
					(thickness 0.15)
				)
				(justify left bottom)
				(hide yes)
			)
		)
		(property "License" "Apache-2.0"
			(at 246.38 80.01 0)
			(effects
				(font
					(size 1.27 1.27)
					(thickness 0.15)
				)
				(justify left bottom)
				(hide yes)
			)
		)
		(pin "A2"
		)
		(pin "A3"
		)
		(pin "A4"
		)
		(pin "A5"
		)
		(pin "B1"
		)
		(pin "B2"
		)
		(pin "B3"
		)
		(pin "B4"
		)
		(pin "B5"
		)
		(pin "C1"
		)
		(pin "C2"
		)
		(pin "C3"
		)
		(pin "C4"
		)
		(pin "C5"
		)
		(pin "D1"
		)
		(pin "D2"
		)
		(pin "D3"
		)
		(pin "D4"
		)
		(pin "D5"
		)
		(pin "E1"
		)
		(pin "E2"
		)
		(pin "E3"
		)
		(pin "E4"
		)
		(pin "E5"
		)
		(instances
			(project "sodimm-ddr5-tester"
				(path ""
					(reference "U1")
					(unit 1)
				)
			)
		)
	)
)
